(kicad_pcb
	(version 20260206)
	(generator "pcbnew")
	(generator_version "10.0")
	(general
		(thickness 1.6)
		(legacy_teardrops no)
	)
	(paper "A4")
	(title_block
		(title "timecard-production-celestica-r4006 — R4006-B0001-02_R01.brd")
		(comment 1 "Time Appliance Project (Time Card) / footprints 160-163 of 1113")
	)
	(layers
		(0 "F.Cu" signal "TOP")
		(4 "In1.Cu" signal "L02_GND1")
		(6 "In2.Cu" signal "L03_SIG1")
		(8 "In3.Cu" signal "L04_GND2")
		(10 "In4.Cu" signal "L05_VCC1")
		(12 "In5.Cu" signal "L06_VCC2")
		(14 "In6.Cu" signal "L07_GND3")
		(16 "In7.Cu" signal "L08_SIG2")
		(18 "In8.Cu" signal "L09_GND4")
		(2 "B.Cu" signal "BOTTOM")
		(9 "F.Adhes" user "F.Adhesive")
		(11 "B.Adhes" user "B.Adhesive")
		(13 "F.Paste" user "Package Geometry/Pastemask Top")
		(15 "B.Paste" user "Package Geometry/Pastemask Bottom")
		(5 "F.SilkS" user "Ref Des/Silkscreen Top")
		(7 "B.SilkS" user "Ref Des/Silkscreen Bottom")
		(1 "F.Mask" user "Board Geometry/Soldermask Top")
		(3 "B.Mask" user "Board Geometry/Soldermask Bottom")
		(17 "Dwgs.User" user "User.Drawings")
		(19 "Cmts.User" user "User.Comments")
		(21 "Eco1.User" user "User.Eco1")
		(23 "Eco2.User" user "User.Eco2")
		(25 "Edge.Cuts" user "Board Geometry/Outline")
		(27 "Margin" user)
		(31 "F.CrtYd" user "Package Geometry/Place Bound Top")
		(29 "B.CrtYd" user "Package Geometry/Place Bound Bottom")
		(35 "F.Fab" user "Ref Des/Assembly Top")
		(33 "B.Fab" user "Ref Des/Assembly Bottom")
	)
	(footprint ""
		(layer "F.Cu")
		(at 12.827 -28.06446 90)
		(property "Reference" "R377"
			(at -0.50546 -2.37363 90)
			(unlocked yes)
			(layer "F.SilkS")
			(effects
				(font
					(size 0.7874 0.5842)
					(thickness 0.1524)
				)
			)
		)
		(property "Value" "VAL*"
			(at 0.02032 2.13233 90)
			(unlocked yes)
			(layer "F.Fab")
			(hide yes)
			(effects
				(font
					(size 0.7874 0.5842)
					(thickness 0.1524)
				)
			)
		)
		(property "Tolerance" "TOL*"
			(at 0.044704 3.05435 90)
			(unlocked yes)
			(layer "Cmts.User")
			(hide yes)
			(effects
				(font
					(size 0.7874 0.5842)
					(thickness 0.1524)
				)
			)
		)
		(property "User Part Number" "PARTNUM*"
			(at 0.02032 4.024884 90)
			(unlocked yes)
			(layer "Cmts.User")
			(hide yes)
			(effects
				(font
					(size 0.7874 0.5842)
					(thickness 0.1524)
				)
			)
		)
		(property "Device Type" "RESISTOR-G155-14701-01,4.7KOHMA"
			(at 0.008382 1.210564 90)
			(unlocked yes)
			(layer "F.Fab")
			(hide yes)
			(effects
				(font
					(size 0.7874 0.5842)
					(thickness 0.1524)
				)
			)
		)
		(duplicate_pad_numbers_are_jumpers no)
		(fp_line
			(start 1.143 -0.5588)
			(end -1.143 -0.5588)
			(stroke
				(width 0.1)
				(type default)
			)
			(layer "F.SilkS")
		)
		(fp_line
			(start -1.143 -0.5588)
			(end -1.143 0.5588)
			(stroke
				(width 0.1)
				(type default)
			)
			(layer "F.SilkS")
		)
		(fp_line
			(start 1.143 0.5588)
			(end 1.143 -0.5588)
			(stroke
				(width 0.1)
				(type default)
			)
			(layer "F.SilkS")
		)
		(fp_line
			(start -1.143 0.5588)
			(end 1.143 0.5588)
			(stroke
				(width 0.1)
				(type default)
			)
			(layer "F.SilkS")
		)
		(fp_rect
			(start 1.143 0.5588)
			(end -1.143 -0.5588)
			(stroke
				(width 0)
				(type default)
			)
			(fill no)
			(layer "F.CrtYd")
		)
		(fp_line
			(start 0.508 -0.3048)
			(end -0.508 -0.3048)
			(stroke
				(width 0.1)
				(type default)
			)
			(layer "F.Fab")
		)
		(fp_line
			(start -0.508 -0.3048)
			(end -0.508 0.3048)
			(stroke
				(width 0.1)
				(type default)
			)
			(layer "F.Fab")
		)
		(fp_line
			(start 0.508 0.3048)
			(end 0.508 -0.3048)
			(stroke
				(width 0.1)
				(type default)
			)
			(layer "F.Fab")
		)
		(fp_line
			(start -0.508 0.3048)
			(end 0.508 0.3048)
			(stroke
				(width 0.1)
				(type default)
			)
			(layer "F.Fab")
		)
		(pad "1" smd rect
			(at -0.5334 0 90)
			(size 0.7112 0.6096)
			(layers "F.Cu" "F.Mask" "F.Paste")
			(net "XP3R3V_FPGA")
		)
		(pad "2" smd rect
			(at 0.5334 0 90)
			(size 0.7112 0.6096)
			(layers "F.Cu" "F.Mask" "F.Paste")
			(net "SMA3_SIG_IN_BF_EN_N")
		)
		(zone
			(layer "F.Cu")
			(hatch none 0.5)
			(connect_pads
				(clearance 0)
			)
			(min_thickness 0.25)
			(keepout
				(tracks not_allowed)
				(vias allowed)
				(pads allowed)
				(copperpour not_allowed)
				(footprints allowed)
			)
			(placement
				(enabled no)
				(sheetname "")
			)
			(fill
				(thermal_gap 0.5)
				(thermal_bridge_width 0.5)
				(island_removal_mode 0)
			)
			(polygon
				(pts
					(xy 13.1318 -28.14066) (xy 12.5222 -28.14066) (xy 12.5222 -27.98826) (xy 13.1318 -27.98826)
				)
			)
		)
		(zone
			(layer "F.Cu")
			(hatch none 0.5)
			(connect_pads
				(clearance 0)
			)
			(min_thickness 0.25)
			(keepout
				(tracks allowed)
				(vias not_allowed)
				(pads allowed)
				(copperpour not_allowed)
				(footprints allowed)
			)
			(placement
				(enabled no)
				(sheetname "")
			)
			(fill
				(thermal_gap 0.5)
				(thermal_bridge_width 0.5)
				(island_removal_mode 0)
			)
			(polygon
				(pts
					(xy 13.1318 -28.14066) (xy 12.5222 -28.14066) (xy 12.5222 -27.98826) (xy 13.1318 -27.98826)
				)
			)
		)
	)
	(footprint ""
		(layer "F.Cu")
		(at 36.957 -80.391 -90)
		(property "Reference" "L24"
			(at -1.5875 -0.03937 90)
			(unlocked yes)
			(layer "F.SilkS")
			(effects
				(font
					(size 0.7874 0.5842)
					(thickness 0.1524)
				)
				(justify left)
			)
		)
		(property "Value" "VAL*"
			(at -0.9398 3.70967 270)
			(unlocked yes)
			(layer "F.Fab")
			(hide yes)
			(effects
				(font
					(size 0.7874 0.5842)
					(thickness 0.1524)
				)
				(justify left)
			)
		)
		(property "Tolerance" "TOL*"
			(at -0.9906 5.00507 270)
			(unlocked yes)
			(layer "Cmts.User")
			(hide yes)
			(effects
				(font
					(size 0.7874 0.5842)
					(thickness 0.1524)
				)
				(justify left)
			)
		)
		(property "User Part Number" "PARTNUM*"
			(at -2.54 2.46507 270)
			(unlocked yes)
			(layer "Cmts.User")
			(hide yes)
			(effects
				(font
					(size 0.7874 0.5842)
					(thickness 0.1524)
				)
				(justify left)
			)
		)
		(property "Device Type" "FERRITEBEAD-G191-10100-01,120OA"
			(at -0.9906 1.22047 270)
			(unlocked yes)
			(layer "F.Fab")
			(hide yes)
			(effects
				(font
					(size 0.7874 0.5842)
					(thickness 0.1524)
				)
				(justify left)
			)
		)
		(duplicate_pad_numbers_are_jumpers no)
		(fp_line
			(start -1.3208 0.7112)
			(end -1.3208 -0.7112)
			(stroke
				(width 0.1)
				(type default)
			)
			(layer "F.SilkS")
		)
		(fp_line
			(start 1.3208 0.7112)
			(end -1.3208 0.7112)
			(stroke
				(width 0.1)
				(type default)
			)
			(layer "F.SilkS")
		)
		(fp_line
			(start -1.3208 -0.7112)
			(end 1.3208 -0.7112)
			(stroke
				(width 0.1)
				(type default)
			)
			(layer "F.SilkS")
		)
		(fp_line
			(start 1.3208 -0.7112)
			(end 1.3208 0.7112)
			(stroke
				(width 0.1)
				(type default)
			)
			(layer "F.SilkS")
		)
		(fp_rect
			(start -1.3208 0.7112)
			(end 1.3208 -0.7112)
			(stroke
				(width 0)
				(type default)
			)
			(fill no)
			(layer "F.CrtYd")
		)
		(fp_line
			(start -0.8128 0.4572)
			(end -0.8128 -0.4572)
			(stroke
				(width 0.1)
				(type default)
			)
			(layer "F.Fab")
		)
		(fp_line
			(start 0.8128 0.4572)
			(end -0.8128 0.4572)
			(stroke
				(width 0.1)
				(type default)
			)
			(layer "F.Fab")
		)
		(fp_line
			(start -0.8128 -0.4572)
			(end 0.8128 -0.4572)
			(stroke
				(width 0.1)
				(type default)
			)
			(layer "F.Fab")
		)
		(fp_line
			(start 0.8128 -0.4572)
			(end 0.8128 0.4572)
			(stroke
				(width 0.1)
				(type default)
			)
			(layer "F.Fab")
		)
		(pad "1" smd rect
			(at -0.6858 0 270)
			(size 0.762 0.8636)
			(layers "F.Cu" "F.Mask" "F.Paste")
			(net "XP3R3V_FPGA")
		)
		(pad "2" smd rect
			(at 0.6858 0 270)
			(size 0.762 0.8636)
			(layers "F.Cu" "F.Mask" "F.Paste")
			(net "XP3R3V_FT4232")
		)
		(zone
			(layer "F.Cu")
			(hatch none 0.5)
			(connect_pads
				(clearance 0)
			)
			(min_thickness 0.25)
			(keepout
				(tracks not_allowed)
				(vias allowed)
				(pads allowed)
				(copperpour not_allowed)
				(footprints allowed)
			)
			(placement
				(enabled no)
				(sheetname "")
			)
			(fill
				(thermal_gap 0.5)
				(thermal_bridge_width 0.5)
				(island_removal_mode 0)
			)
			(polygon
				(pts
					(xy 36.4998 -80.5434) (xy 36.4998 -80.2386) (xy 37.4142 -80.2386) (xy 37.4142 -80.5434)
				)
			)
		)
		(zone
			(layer "F.Cu")
			(hatch none 0.5)
			(connect_pads
				(clearance 0)
			)
			(min_thickness 0.25)
			(keepout
				(tracks allowed)
				(vias not_allowed)
				(pads allowed)
				(copperpour not_allowed)
				(footprints allowed)
			)
			(placement
				(enabled no)
				(sheetname "")
			)
			(fill
				(thermal_gap 0.5)
				(thermal_bridge_width 0.5)
				(island_removal_mode 0)
			)
			(polygon
				(pts
					(xy 36.4998 -80.5434) (xy 36.4998 -80.2386) (xy 37.4142 -80.2386) (xy 37.4142 -80.5434)
				)
			)
		)
	)
	(footprint ""
		(layer "F.Cu")
		(at 37.1094 -102.3874 180)
		(property "Reference" "C43"
			(at 4.2164 1.71323 0)
			(unlocked yes)
			(layer "F.SilkS")
			(effects
				(font
					(size 0.7874 0.5842)
					(thickness 0.1524)
				)
			)
		)
		(property "Value" "VAL*"
			(at 0.193548 2.13614 180)
			(unlocked yes)
			(layer "F.Fab")
			(hide yes)
			(effects
				(font
					(size 0.7874 0.5842)
					(thickness 0.1524)
				)
			)
		)
		(property "Tolerance" "TOL*"
			(at 0.216154 3.1496 180)
			(unlocked yes)
			(layer "Cmts.User")
			(hide yes)
			(effects
				(font
					(size 0.7874 0.5842)
					(thickness 0.1524)
				)
			)
		)
		(property "Device Type" "CAPACITOR-G104-0A180-FJ,18PF,5%"
			(at 0.184404 1.180592 180)
			(unlocked yes)
			(layer "F.Fab")
			(hide yes)
			(effects
				(font
					(size 0.7874 0.5842)
					(thickness 0.1524)
				)
			)
		)
		(property "User Part Number" "PARTNUM*"
			(at 0.216154 4.185666 180)
			(unlocked yes)
			(layer "Cmts.User")
			(hide yes)
			(effects
				(font
					(size 0.7874 0.5842)
					(thickness 0.1524)
				)
			)
		)
		(duplicate_pad_numbers_are_jumpers no)
		(fp_line
			(start 0.671322 0.4445)
			(end -0.671322 0.4445)
			(stroke
				(width 0.1)
				(type default)
			)
			(layer "F.SilkS")
		)
		(fp_line
			(start 0.671322 -0.4445)
			(end 0.671322 0.4445)
			(stroke
				(width 0.1)
				(type default)
			)
			(layer "F.SilkS")
		)
		(fp_line
			(start -0.671322 0.4445)
			(end -0.671322 -0.4445)
			(stroke
				(width 0.1)
				(type default)
			)
			(layer "F.SilkS")
		)
		(fp_line
			(start -0.671322 -0.4445)
			(end 0.671322 -0.4445)
			(stroke
				(width 0.1)
				(type default)
			)
			(layer "F.SilkS")
		)
		(fp_rect
			(start -0.671322 0.4445)
			(end 0.671322 -0.4445)
			(stroke
				(width 0)
				(type default)
			)
			(fill no)
			(layer "F.CrtYd")
		)
		(fp_line
			(start 0.31496 0.1651)
			(end 0.31496 -0.1651)
			(stroke
				(width 0.1)
				(type default)
			)
			(layer "F.Fab")
		)
		(fp_line
			(start 0.31496 -0.1651)
			(end -0.31496 -0.1651)
			(stroke
				(width 0.1)
				(type default)
			)
			(layer "F.Fab")
		)
		(fp_line
			(start -0.31496 0.1651)
			(end 0.31496 0.1651)
			(stroke
				(width 0.1)
				(type default)
			)
			(layer "F.Fab")
		)
		(fp_line
			(start -0.31496 -0.1651)
			(end -0.31496 0.1651)
			(stroke
				(width 0.1)
				(type default)
			)
			(layer "F.Fab")
		)
		(pad "1" smd rect
			(at -0.264922 0 180)
			(size 0.3048 0.381)
			(layers "F.Cu" "F.Mask" "F.Paste")
			(net "XP5R0V_COMP")
		)
		(pad "2" smd rect
			(at 0.264922 0 180)
			(size 0.3048 0.381)
			(layers "F.Cu" "F.Mask" "F.Paste")
			(net "XP5R0V_AGND")
		)
		(zone
			(layer "F.Cu")
			(hatch none 0.5)
			(connect_pads
				(clearance 0)
			)
			(min_thickness 0.25)
			(keepout
				(tracks allowed)
				(vias not_allowed)
				(pads allowed)
				(copperpour not_allowed)
				(footprints allowed)
			)
			(placement
				(enabled no)
				(sheetname "")
			)
			(fill
				(thermal_gap 0.5)
				(thermal_bridge_width 0.5)
				(island_removal_mode 0)
			)
			(polygon
				(pts
					(xy 37.221922 -102.5779) (xy 36.996878 -102.5779) (xy 36.996878 -102.1969) (xy 37.221922 -102.1969)
				)
			)
		)
	)
	(footprint ""
		(layer "F.Cu")
		(at 72.35444 -46.746668 -90)
		(property "Reference" "P1"
			(at 0.558038 -4.60756 0)
			(unlocked yes)
			(layer "F.SilkS")
			(effects
				(font
					(size 0.7874 0.5842)
					(thickness 0.1524)
				)
			)
		)
		(property "Value" ""
			(at 0 0 270)
			(layer "F.Fab")
			(effects
				(font
					(size 1.27 1.27)
				)
			)
		)
		(property "User Part Number" "PARTNUM*"
			(at 0.051054 6.007608 270)
			(unlocked yes)
			(layer "Cmts.User")
			(hide yes)
			(effects
				(font
					(size 0.7874 0.5842)
					(thickness 0.1524)
				)
			)
		)
		(property "Device Type" "CONN_HDR_2X10_M_S_SMT-G200-130A"
			(at 0.051054 4.813808 270)
			(unlocked yes)
			(layer "F.Fab")
			(hide yes)
			(effects
				(font
					(size 0.7874 0.5842)
					(thickness 0.1524)
				)
			)
		)
		(duplicate_pad_numbers_are_jumpers no)
		(fp_line
			(start -4.01828 3.155696)
			(end 4.754118 3.155696)
			(stroke
				(width 0.1)
				(type default)
			)
			(layer "F.SilkS")
		)
		(fp_line
			(start 4.754118 3.155696)
			(end 4.754118 -3.155696)
			(stroke
				(width 0.1)
				(type default)
			)
			(layer "F.SilkS")
		)
		(fp_line
			(start -4.754118 2.419858)
			(end -4.01828 3.155696)
			(stroke
				(width 0.1)
				(type default)
			)
			(layer "F.SilkS")
		)
		(fp_line
			(start -4.754118 -3.155696)
			(end -4.754118 2.419858)
			(stroke
				(width 0.1)
				(type default)
			)
			(layer "F.SilkS")
		)
		(fp_line
			(start 4.754118 -3.155696)
			(end -4.754118 -3.155696)
			(stroke
				(width 0.1)
				(type default)
			)
			(layer "F.SilkS")
		)
		(fp_poly
			(pts
				(xy -5.008118 2.525014) (xy -5.008118 -3.409696) (xy 5.008118 -3.409696) (xy 5.008118 3.409696)
				(xy -4.123436 3.409696)
			)
			(stroke
				(width 0)
				(type default)
			)
			(fill no)
			(layer "F.CrtYd")
		)
		(fp_line
			(start -4.01447 2.800096)
			(end -4.500118 2.314702)
			(stroke
				(width 0.1)
				(type default)
			)
			(layer "F.Fab")
		)
		(fp_line
			(start 4.500118 2.800096)
			(end -4.01447 2.800096)
			(stroke
				(width 0.1)
				(type default)
			)
			(layer "F.Fab")
		)
		(fp_line
			(start -4.500118 2.314702)
			(end -4.500118 -2.800096)
			(stroke
				(width 0.1)
				(type default)
			)
			(layer "F.Fab")
		)
		(fp_line
			(start -4.500118 -2.800096)
			(end 4.500118 -2.800096)
			(stroke
				(width 0.1)
				(type default)
			)
			(layer "F.Fab")
		)
		(fp_line
			(start 4.500118 -2.800096)
			(end 4.500118 2.800096)
			(stroke
				(width 0.1)
				(type default)
			)
			(layer "F.Fab")
		)
		(fp_text user "1"
			(at -2.624582 3.77444 0)
			(unlocked yes)
			(layer "F.SilkS")
			(effects
				(font
					(size 0.635 0.4064)
					(thickness 0.1524)
				)
			)
		)
		(fp_text user "19"
			(at 2.455418 3.77444 0)
			(unlocked yes)
			(layer "F.SilkS")
			(effects
				(font
					(size 0.635 0.4064)
					(thickness 0.1524)
				)
			)
		)
		(fp_text user "2"
			(at -2.624582 -3.71856 0)
			(unlocked yes)
			(layer "F.SilkS")
			(effects
				(font
					(size 0.635 0.4064)
					(thickness 0.1524)
				)
			)
		)
		(fp_text user "20"
			(at 1.693418 -4.09956 0)
			(unlocked yes)
			(layer "F.SilkS")
			(effects
				(font
					(size 0.635 0.4064)
					(thickness 0.1524)
				)
			)
		)
		(fp_text user "19"
			(at 3.085338 3.77444 0)
			(unlocked yes)
			(layer "F.Fab")
			(effects
				(font
					(size 0.7874 0.5842)
					(thickness 0.1524)
				)
			)
		)
		(fp_text user "1"
			(at -2.687066 3.14071 0)
			(unlocked yes)
			(layer "F.Fab")
			(effects
				(font
					(size 0.7874 0.5842)
					(thickness 0.1524)
				)
			)
		)
		(fp_text user "2"
			(at -1.875536 -3.850386 0)
			(unlocked yes)
			(layer "F.Fab")
			(effects
				(font
					(size 0.7874 0.5842)
					(thickness 0.1524)
				)
			)
		)
		(fp_text user "20"
			(at 2.980436 -3.89128 0)
			(unlocked yes)
			(layer "F.Fab")
			(effects
				(font
					(size 0.7874 0.5842)
					(thickness 0.1524)
				)
			)
		)
		(pad "1" smd rect
			(at -2.249932 1.999996 270)
			(size 0.254 1.8034)
			(layers "F.Cu" "F.Mask" "F.Paste")
			(net "R_MAC_PPS_IN1P")
		)
		(pad "2" smd rect
			(at -2.249932 -1.999996 270)
			(size 0.254 1.8034)
			(layers "F.Cu" "F.Mask" "F.Paste")
			(net "R_MAC_USB_DP")
		)
		(pad "3" smd rect
			(at -1.75006 1.999996 270)
			(size 0.254 1.8034)
			(layers "F.Cu" "F.Mask" "F.Paste")
			(net "R_MAC_PPS_IN1N")
		)
		(pad "4" smd rect
			(at -1.75006 -1.999996 270)
			(size 0.254 1.8034)
			(layers "F.Cu" "F.Mask" "F.Paste")
			(net "R_MAC_USB_DM")
		)
		(pad "5" smd rect
			(at -1.249934 1.999996 270)
			(size 0.254 1.8034)
			(layers "F.Cu" "F.Mask" "F.Paste")
			(net "R_MAC_PPS_IN0P")
		)
		(pad "6" smd rect
			(at -1.249934 -1.999996 270)
			(size 0.254 1.8034)
			(layers "F.Cu" "F.Mask" "F.Paste")
			(net "XP5R0V_MAC_USB")
		)
		(pad "7" smd rect
			(at -0.750062 1.999996 270)
			(size 0.254 1.8034)
			(layers "F.Cu" "F.Mask" "F.Paste")
			(net "R_MAC_PPS_IN0N")
		)
		(pad "8" smd rect
			(at -0.750062 -1.999996 270)
			(size 0.254 1.8034)
			(layers "F.Cu" "F.Mask" "F.Paste")
			(net "SG")
		)
		(pad "9" smd rect
			(at -0.249936 1.999996 270)
			(size 0.254 1.8034)
			(layers "F.Cu" "F.Mask" "F.Paste")
			(net "SG")
		)
		(pad "10" smd rect
			(at -0.249936 -1.999996 270)
			(size 0.254 1.8034)
			(layers "F.Cu" "F.Mask" "F.Paste")
			(net "Net_773")
		)
		(pad "11" smd rect
			(at 0.249936 1.999996 270)
			(size 0.254 1.8034)
			(layers "F.Cu" "F.Mask" "F.Paste")
			(net "Net_772")
		)
		(pad "12" smd rect
			(at 0.249936 -1.999996 270)
			(size 0.254 1.8034)
			(layers "F.Cu" "F.Mask" "F.Paste")
			(net "Net_771")
		)
		(pad "13" smd rect
			(at 0.750062 1.999996 270)
			(size 0.254 1.8034)
			(layers "F.Cu" "F.Mask" "F.Paste")
			(net "Net_770")
		)
		(pad "14" smd rect
			(at 0.750062 -1.999996 270)
			(size 0.254 1.8034)
			(layers "F.Cu" "F.Mask" "F.Paste")
			(net "Net_769")
		)
		(pad "15" smd rect
			(at 1.249934 1.999996 270)
			(size 0.254 1.8034)
			(layers "F.Cu" "F.Mask" "F.Paste")
			(net "SG")
		)
		(pad "16" smd rect
			(at 1.249934 -1.999996 270)
			(size 0.254 1.8034)
			(layers "F.Cu" "F.Mask" "F.Paste")
			(net "Net_768")
		)
		(pad "17" smd rect
			(at 1.75006 1.999996 270)
			(size 0.254 1.8034)
			(layers "F.Cu" "F.Mask" "F.Paste")
			(net "R_MAC_PPS_OUTP")
		)
		(pad "18" smd rect
			(at 1.75006 -1.999996 270)
			(size 0.254 1.8034)
			(layers "F.Cu" "F.Mask" "F.Paste")
			(net "Net_767")
		)
		(pad "19" smd rect
			(at 2.249932 1.999996 270)
			(size 0.254 1.8034)
			(layers "F.Cu" "F.Mask" "F.Paste")
			(net "R_MAC_PPS_OUTN")
		)
		(pad "20" smd rect
			(at 2.249932 -1.999996 270)
			(size 0.254 1.8034)
			(layers "F.Cu" "F.Mask" "F.Paste")
			(net "MAC_ALARM")
		)
	)
)
